(kicad_pcb
	(version 20260206)
	(generator "pcbnew")
	(generator_version "10.0")
	(general
		(thickness 1.6)
		(legacy_teardrops no)
	)
	(paper "A4")
	(title_block
		(title "Wiwynn_Tioga_Pass_MB.brd")
		(comment 1 "Tioga Pass / footprint 1664 of 4770 (U7C1), pads 814-921 of 1310")
	)
	(layers
		(0 "F.Cu" signal "TOP")
		(4 "In1.Cu" signal "L2GND")
		(6 "In2.Cu" signal "L3")
		(8 "In3.Cu" signal "L4GND")
		(10 "In4.Cu" signal "L5")
		(12 "In5.Cu" signal "L6GND")
		(14 "In6.Cu" signal "L7VCC")
		(16 "In7.Cu" signal "L8VCC")
		(18 "In8.Cu" signal "L9GND")
		(20 "In9.Cu" signal "L10")
		(22 "In10.Cu" signal "L11GND")
		(24 "In11.Cu" signal "L12")
		(26 "In12.Cu" signal "L13GND")
		(2 "B.Cu" signal "BOTTOM")
		(9 "F.Adhes" user "F.Adhesive")
		(11 "B.Adhes" user "B.Adhesive")
		(13 "F.Paste" user "Package Geometry/Pastemask Top")
		(15 "B.Paste" user "Package Geometry/Pastemask Bottom")
		(5 "F.SilkS" user "Ref Des/Silkscreen Top")
		(7 "B.SilkS" user "Ref Des/Silkscreen Bottom")
		(1 "F.Mask" user "Board Geometry/Soldermask Top")
		(3 "B.Mask" user "Board Geometry/Soldermask Bottom")
		(17 "Dwgs.User" user "User.Drawings")
		(19 "Cmts.User" user "User.Comments")
		(21 "Eco1.User" user "User.Eco1")
		(23 "Eco2.User" user "User.Eco2")
		(25 "Edge.Cuts" user "Board Geometry/Outline")
		(27 "Margin" user)
		(31 "F.CrtYd" user "Package Geometry/Place Bound Top")
		(29 "B.CrtYd" user "Package Geometry/Place Bound Bottom")
		(35 "F.Fab" user "Ref Des/Assembly Top")
		(33 "B.Fab" user "Ref Des/Assembly Bottom")
	)
	(footprint ""
		(layer "F.Cu")
		(at 387.985 -109.855 90)
		(property "Reference" "U7C1"
			(at 17.75333 -13.335 0)
			(unlocked yes)
			(layer "F.SilkS")
			(effects
				(font
					(size 0.7874 0.5842)
					(thickness 0.1524)
				)
				(justify left)
			)
		)
		(property "Value" ""
			(at 0 0 90)
			(layer "F.Fab")
			(effects
				(font
					(size 1.27 1.27)
				)
			)
		)
		(duplicate_pad_numbers_are_jumpers no)
		(pad "BV16" smd circle
			(at -9.500108 12.065 270)
			(size 0.3048 0.3048)
			(layers "F.Cu" "F.Mask" "F.Paste")
			(net "XTAL_KR_25M_IN")
		)
		(pad "BV19" smd circle
			(at -8.50011 12.065 270)
			(size 0.3048 0.3048)
			(layers "F.Cu" "F.Mask" "F.Paste")
			(net "RST_BMC_SYSRST_BTN_OUT_B_N")
		)
		(pad "BV21" smd circle
			(at -7.500112 12.065 270)
			(size 0.3048 0.3048)
			(layers "F.Cu" "F.Mask" "F.Paste")
			(net "JTAG_PCH_GBE_CLK")
		)
		(pad "BV23" smd circle
			(at -6.500114 12.065 270)
			(size 0.3048 0.3048)
			(layers "F.Cu" "F.Mask" "F.Paste")
			(net "FM_CPU1_RC_ERROR_R_N")
		)
		(pad "BV25" smd circle
			(at -5.500116 12.065 270)
			(size 0.3048 0.3048)
			(layers "F.Cu" "F.Mask" "F.Paste")
			(net "FM_BIOS_MRC_DEBUG_MSG_DIS_N")
		)
		(pad "BV27" smd circle
			(at -4.500118 12.065 270)
			(size 0.3048 0.3048)
			(layers "F.Cu" "F.Mask" "F.Paste")
			(net "SMB_HOST_STBY_LVC3_SDA_R1")
		)
		(pad "BV29" smd circle
			(at -3.50012 12.065 270)
			(size 0.3048 0.3048)
			(layers "F.Cu" "F.Mask" "F.Paste")
			(net "SMB_SMLINK0_STBY_LVC3_SCL_R1")
		)
		(pad "BV31" smd circle
			(at -2.500122 12.065 270)
			(size 0.3048 0.3048)
			(layers "F.Cu" "F.Mask" "F.Paste")
			(net "FM_PCH_SATA_RAID_KEY")
		)
		(pad "BV33" smd circle
			(at -1.500124 12.065 270)
			(size 0.3048 0.3048)
			(layers "F.Cu" "F.Mask" "F.Paste")
			(net "FM_BOARD_REV_ID2")
		)
		(pad "BV35" smd circle
			(at -0.500126 12.065 270)
			(size 0.3048 0.3048)
			(layers "F.Cu" "F.Mask" "F.Paste")
			(net "SMB_PMBUS_BMC_STBY_LVC3_SDA_R1")
		)
		(pad "BV38" smd circle
			(at 0.500126 12.065 270)
			(size 0.3048 0.3048)
			(layers "F.Cu" "F.Mask" "F.Paste")
			(net "FM_BOARD_REV_ID1")
		)
		(pad "BV40" smd circle
			(at 1.500124 12.065 270)
			(size 0.3048 0.3048)
			(layers "F.Cu" "F.Mask" "F.Paste")
			(net "GND")
		)
		(pad "BV42" smd circle
			(at 2.500122 12.065 270)
			(size 0.3048 0.3048)
			(layers "F.Cu" "F.Mask" "F.Paste")
			(net "IRQ_OOB_MGMT_RISER_ALERT_N")
		)
		(pad "BV44" smd circle
			(at 3.50012 12.065 270)
			(size 0.3048 0.3048)
			(layers "F.Cu" "F.Mask" "F.Paste")
			(net "Net_477")
		)
		(pad "BV47" smd circle
			(at 4.500118 12.065 270)
			(size 0.3048 0.3048)
			(layers "F.Cu" "F.Mask" "F.Paste")
			(net "H_CPU0_FAST_WAKE_LVT3_N")
		)
		(pad "BV49" smd circle
			(at 5.500116 12.065 270)
			(size 0.3048 0.3048)
			(layers "F.Cu" "F.Mask" "F.Paste")
			(net "GND")
		)
		(pad "BV51" smd circle
			(at 6.500114 12.065 270)
			(size 0.3048 0.3048)
			(layers "F.Cu" "F.Mask" "F.Paste")
			(net "TP_CLK_24M_PMSYNC2")
		)
		(pad "BV53" smd circle
			(at 7.500112 12.065 270)
			(size 0.3048 0.3048)
			(layers "F.Cu" "F.Mask" "F.Paste")
			(net "TP_USB2_P13_DP")
		)
		(pad "BV55" smd circle
			(at 8.50011 12.065 270)
			(size 0.3048 0.3048)
			(layers "F.Cu" "F.Mask" "F.Paste")
			(net "TP_USB2_P9_DP")
		)
		(pad "BV58" smd circle
			(at 9.500108 12.065 270)
			(size 0.3048 0.3048)
			(layers "F.Cu" "F.Mask" "F.Paste")
			(net "USB2_PCH_BMC_P5_DP_R")
		)
		(pad "BV60" smd circle
			(at 10.500106 12.065 270)
			(size 0.3048 0.3048)
			(layers "F.Cu" "F.Mask" "F.Paste")
			(net "USB2_P01_DP")
		)
		(pad "BV62" smd circle
			(at 11.500104 12.065 270)
			(size 0.3048 0.3048)
			(layers "F.Cu" "F.Mask" "F.Paste")
			(net "USB_PCH_BMC_P4_DP_R")
		)
		(pad "BV64" smd circle
			(at 12.500102 12.065 270)
			(size 0.3048 0.3048)
			(layers "F.Cu" "F.Mask" "F.Paste")
			(net "TP_USB2_P8_DP")
		)
		(pad "BV66" smd circle
			(at 13.5001 12.065 270)
			(size 0.3048 0.3048)
			(layers "F.Cu" "F.Mask" "F.Paste")
			(net "TP_USB2_P12_DP")
		)
		(pad "BW1" smd circle
			(at -16.310102 12.502134 225)
			(size 0.5588 0.5588)
			(layers "F.Cu" "F.Mask" "F.Paste")
			(net "GND")
		)
		(pad "BW3" smd circle
			(at -15.497302 12.497308 180)
			(size 0.4064 0.4064)
			(layers "F.Cu" "F.Mask" "F.Paste")
			(net "TP_PCH_RSVD46")
		)
		(pad "BW5" smd circle
			(at -14.784324 12.580112 90)
			(size 0.3556 0.3556)
			(layers "F.Cu" "F.Mask" "F.Paste")
			(net "SMB_PCH_MEZZ_LOM1_SCL")
		)
		(pad "BW6" smd circle
			(at -13.999972 12.580112 90)
			(size 0.3556 0.3556)
			(layers "F.Cu" "F.Mask" "F.Paste")
			(net "SMB_PCH_MEZZ_LOM3_SCL")
		)
		(pad "BW9" smd circle
			(at -12.999974 12.480036 270)
			(size 0.3048 0.3048)
			(layers "F.Cu" "F.Mask" "F.Paste")
			(net "SMB_PCH_MEZZ_LOM3_SDA")
		)
		(pad "BW11" smd circle
			(at -11.999976 12.480036 270)
			(size 0.3048 0.3048)
			(layers "F.Cu" "F.Mask" "F.Paste")
			(net "SMB_PCH_MEZZ_LOM2_SDA")
		)
		(pad "BW13" smd circle
			(at -10.999978 12.480036 270)
			(size 0.3048 0.3048)
			(layers "F.Cu" "F.Mask" "F.Paste")
			(net "FM_GBE2_LVC3_MOD_ABS")
		)
		(pad "BW15" smd circle
			(at -9.99998 12.480036 270)
			(size 0.3048 0.3048)
			(layers "F.Cu" "F.Mask" "F.Paste")
			(net "GND")
		)
		(pad "BW18" smd circle
			(at -8.999982 12.480036 270)
			(size 0.3048 0.3048)
			(layers "F.Cu" "F.Mask" "F.Paste")
			(net "GND")
		)
		(pad "BW20" smd circle
			(at -7.999984 12.480036 270)
			(size 0.3048 0.3048)
			(layers "F.Cu" "F.Mask" "F.Paste")
			(net "IRQ_DIMM_SAVE_LVT3_R_N")
		)
		(pad "BW22" smd circle
			(at -6.999986 12.480036 270)
			(size 0.3048 0.3048)
			(layers "F.Cu" "F.Mask" "F.Paste")
			(net "PU_10GBE_LOM_PCI_DISABLE_N")
		)
		(pad "BW24" smd circle
			(at -5.999988 12.480036 270)
			(size 0.3048 0.3048)
			(layers "F.Cu" "F.Mask" "F.Paste")
			(net "IRQ_BOARD_BMC_ALERT_N")
		)
		(pad "BW26" smd circle
			(at -4.99999 12.480036 270)
			(size 0.3048 0.3048)
			(layers "F.Cu" "F.Mask" "F.Paste")
			(net "GND")
		)
		(pad "BW28" smd circle
			(at -3.999992 12.480036 270)
			(size 0.3048 0.3048)
			(layers "F.Cu" "F.Mask" "F.Paste")
			(net "SMB_HOST_STBY_LVC3_SCL_R1")
		)
		(pad "BW30" smd circle
			(at -2.999994 12.480036 270)
			(size 0.3048 0.3048)
			(layers "F.Cu" "F.Mask" "F.Paste")
			(net "SMB_SMLINK0_STBY_LVC3_SDA_R1")
		)
		(pad "BW32" smd circle
			(at -1.999996 12.480036 270)
			(size 0.3048 0.3048)
			(layers "F.Cu" "F.Mask" "F.Paste")
			(net "FM_PASSWORD_CLEAR_N")
		)
		(pad "BW34" smd circle
			(at -0.999998 12.480036 270)
			(size 0.3048 0.3048)
			(layers "F.Cu" "F.Mask" "F.Paste")
			(net "IRQ_SML0_ALERT_N")
		)
		(pad "BW37" smd circle
			(at 0 12.480036 270)
			(size 0.3048 0.3048)
			(layers "F.Cu" "F.Mask" "F.Paste")
			(net "FM_SLT_CFG1")
		)
		(pad "BW39" smd circle
			(at 0.999998 12.480036 270)
			(size 0.3048 0.3048)
			(layers "F.Cu" "F.Mask" "F.Paste")
			(net "FM_BB_BMC_MP_GPIO")
		)
		(pad "BW41" smd circle
			(at 1.999996 12.480036 270)
			(size 0.3048 0.3048)
			(layers "F.Cu" "F.Mask" "F.Paste")
			(net "FM_CPLD_BMC_PWRDN_N")
		)
		(pad "BW43" smd circle
			(at 2.999994 12.480036 270)
			(size 0.3048 0.3048)
			(layers "F.Cu" "F.Mask" "F.Paste")
			(net "SGPIO_PCH_SSATA_DOUT0")
		)
		(pad "BW45" smd circle
			(at 3.999992 12.480036 270)
			(size 0.3048 0.3048)
			(layers "F.Cu" "F.Mask" "F.Paste")
			(net "IRQ_MEZZ_LAN_ALERT_N")
		)
		(pad "BW48" smd circle
			(at 4.99999 12.480036 270)
			(size 0.3048 0.3048)
			(layers "F.Cu" "F.Mask" "F.Paste")
			(net "FM_XRC_PRESENT_N")
		)
		(pad "BW50" smd circle
			(at 5.999988 12.480036 270)
			(size 0.3048 0.3048)
			(layers "F.Cu" "F.Mask" "F.Paste")
			(net "CLK_48M_USB_BMC")
		)
		(pad "BW52" smd circle
			(at 6.999986 12.480036 270)
			(size 0.3048 0.3048)
			(layers "F.Cu" "F.Mask" "F.Paste")
			(net "GND")
		)
		(pad "BW54" smd circle
			(at 7.999984 12.480036 270)
			(size 0.3048 0.3048)
			(layers "F.Cu" "F.Mask" "F.Paste")
			(net "TP_USB2_P11_DP")
		)
		(pad "BW57" smd circle
			(at 8.999982 12.480036 270)
			(size 0.3048 0.3048)
			(layers "F.Cu" "F.Mask" "F.Paste")
			(net "TP_USB2_P07_DP")
		)
		(pad "BW59" smd circle
			(at 9.99998 12.480036 270)
			(size 0.3048 0.3048)
			(layers "F.Cu" "F.Mask" "F.Paste")
			(net "TP_USB2_P03_DP")
		)
		(pad "BW61" smd circle
			(at 10.999978 12.480036 270)
			(size 0.3048 0.3048)
			(layers "F.Cu" "F.Mask" "F.Paste")
			(net "USB2_P02_DP_R")
		)
		(pad "BW63" smd circle
			(at 11.999976 12.480036 270)
			(size 0.3048 0.3048)
			(layers "F.Cu" "F.Mask" "F.Paste")
			(net "TP_USB2_P06_DP")
		)
		(pad "BW65" smd circle
			(at 12.999974 12.480036 270)
			(size 0.3048 0.3048)
			(layers "F.Cu" "F.Mask" "F.Paste")
			(net "TP_USB2_P10_DN")
		)
		(pad "BW67" smd circle
			(at 13.999972 12.580112 90)
			(size 0.3556 0.3556)
			(layers "F.Cu" "F.Mask" "F.Paste")
			(net "TP_USB2_P12_DN")
		)
		(pad "BW68" smd circle
			(at 14.784324 12.580112 90)
			(size 0.3556 0.3556)
			(layers "F.Cu" "F.Mask" "F.Paste")
			(net "TP_USB2_P14_DN")
		)
		(pad "BW70" smd circle
			(at 15.497302 12.497308 315)
			(size 0.4064 0.4064)
			(layers "F.Cu" "F.Mask" "F.Paste")
			(net "GND")
		)
		(pad "BW72" smd circle
			(at 16.310102 12.502134 315)
			(size 0.5588 0.5588)
			(layers "F.Cu" "F.Mask" "F.Paste")
			(net "GND")
		)
		(pad "BY10" smd circle
			(at -12.500102 12.895072 270)
			(size 0.3048 0.3048)
			(layers "F.Cu" "F.Mask" "F.Paste")
			(net "FM_GBE1_LVC3_MOD_ABS")
		)
		(pad "BY12" smd circle
			(at -11.500104 12.895072 270)
			(size 0.3048 0.3048)
			(layers "F.Cu" "F.Mask" "F.Paste")
			(net "FM_GBE3_LVC3_MOD_ABS")
		)
		(pad "BY14" smd circle
			(at -10.500106 12.895072 270)
			(size 0.3048 0.3048)
			(layers "F.Cu" "F.Mask" "F.Paste")
			(net "TP_PCH_GPP_J19")
		)
		(pad "BY16" smd circle
			(at -9.500108 12.895072 270)
			(size 0.3048 0.3048)
			(layers "F.Cu" "F.Mask" "F.Paste")
			(net "XTAL_KR_25M_OUT")
		)
		(pad "BY19" smd circle
			(at -8.50011 12.895072 270)
			(size 0.3048 0.3048)
			(layers "F.Cu" "F.Mask" "F.Paste")
			(net "PWRGD_SYS_PWROK")
		)
		(pad "BY21" smd circle
			(at -7.500112 12.895072 270)
			(size 0.3048 0.3048)
			(layers "F.Cu" "F.Mask" "F.Paste")
			(net "FM_10GBE_LOM_DISABLE_N")
		)
		(pad "BY23" smd circle
			(at -6.500114 12.895072 270)
			(size 0.3048 0.3048)
			(layers "F.Cu" "F.Mask" "F.Paste")
			(net "JTAG_PCH_GBE_TDI")
		)
		(pad "BY25" smd circle
			(at -5.500116 12.895072 270)
			(size 0.3048 0.3048)
			(layers "F.Cu" "F.Mask" "F.Paste")
			(net "A_RCOMP_3P3")
		)
		(pad "BY27" smd circle
			(at -4.500118 12.895072 270)
			(size 0.3048 0.3048)
			(layers "F.Cu" "F.Mask" "F.Paste")
			(net "PU_PCH_TLS_ENABLE_STRAP")
		)
		(pad "BY29" smd circle
			(at -3.50012 12.895072 270)
			(size 0.3048 0.3048)
			(layers "F.Cu" "F.Mask" "F.Paste")
			(net "FM_CPU1_RC_EN")
		)
		(pad "BY31" smd circle
			(at -2.500122 12.895072 270)
			(size 0.3048 0.3048)
			(layers "F.Cu" "F.Mask" "F.Paste")
			(net "FM_SLT_CFG2_R")
		)
		(pad "BY33" smd circle
			(at -1.500124 12.895072 270)
			(size 0.3048 0.3048)
			(layers "F.Cu" "F.Mask" "F.Paste")
			(net "FM_BIOS_POST_CMPLT_N")
		)
		(pad "BY35" smd circle
			(at -0.500126 12.895072 270)
			(size 0.3048 0.3048)
			(layers "F.Cu" "F.Mask" "F.Paste")
			(net "FM_PMBUS_ALERT_BUF_EN_R_N")
		)
		(pad "BY38" smd circle
			(at 0.500126 12.895072 270)
			(size 0.3048 0.3048)
			(layers "F.Cu" "F.Mask" "F.Paste")
			(net "IRQ_BMC_PCH_SCI_LPC_N")
		)
		(pad "BY40" smd circle
			(at 1.500124 12.895072 270)
			(size 0.3048 0.3048)
			(layers "F.Cu" "F.Mask" "F.Paste")
			(net "GND")
		)
		(pad "BY42" smd circle
			(at 2.500122 12.895072 270)
			(size 0.3048 0.3048)
			(layers "F.Cu" "F.Mask" "F.Paste")
			(net "IRQ_FORCE_NM_THROTTLE_N")
		)
		(pad "BY44" smd circle
			(at 3.50012 12.895072 270)
			(size 0.3048 0.3048)
			(layers "F.Cu" "F.Mask" "F.Paste")
			(net "SMB_SLOTX24_PCH_STBY_LVC3_SCL")
		)
		(pad "BY47" smd circle
			(at 4.500118 12.895072 270)
			(size 0.3048 0.3048)
			(layers "F.Cu" "F.Mask" "F.Paste")
			(net "IRQ_LOM_ALERT_N")
		)
		(pad "BY49" smd circle
			(at 5.500116 12.895072 270)
			(size 0.3048 0.3048)
			(layers "F.Cu" "F.Mask" "F.Paste")
			(net "GND")
		)
		(pad "BY51" smd circle
			(at 6.500114 12.895072 270)
			(size 0.3048 0.3048)
			(layers "F.Cu" "F.Mask" "F.Paste")
			(net "H_PMSYNC_CLK_24M_R")
		)
		(pad "BY53" smd circle
			(at 7.500112 12.895072 270)
			(size 0.3048 0.3048)
			(layers "F.Cu" "F.Mask" "F.Paste")
			(net "TP_USB2_P13_DN")
		)
		(pad "BY55" smd circle
			(at 8.50011 12.895072 270)
			(size 0.3048 0.3048)
			(layers "F.Cu" "F.Mask" "F.Paste")
			(net "TP_USB2_P9_DN")
		)
		(pad "BY58" smd circle
			(at 9.500108 12.895072 270)
			(size 0.3048 0.3048)
			(layers "F.Cu" "F.Mask" "F.Paste")
			(net "USB2_PCH_BMC_P5_DN_R")
		)
		(pad "BY60" smd circle
			(at 10.500106 12.895072 270)
			(size 0.3048 0.3048)
			(layers "F.Cu" "F.Mask" "F.Paste")
			(net "USB2_P01_DN")
		)
		(pad "BY62" smd circle
			(at 11.500104 12.895072 270)
			(size 0.3048 0.3048)
			(layers "F.Cu" "F.Mask" "F.Paste")
			(net "USB_PCH_BMC_P4_DN_R")
		)
		(pad "BY64" smd circle
			(at 12.500102 12.895072 270)
			(size 0.3048 0.3048)
			(layers "F.Cu" "F.Mask" "F.Paste")
			(net "TP_USB2_P8_DN")
		)
		(pad "C3" smd circle
			(at -15.497302 -12.497308 135)
			(size 0.4064 0.4064)
			(layers "F.Cu" "F.Mask" "F.Paste")
			(net "GND")
		)
		(pad "C5" smd circle
			(at -14.784324 -12.580112 90)
			(size 0.3556 0.3556)
			(layers "F.Cu" "F.Mask" "F.Paste")
			(net "TP_PCH_RSVD16")
		)
		(pad "C6" smd circle
			(at -13.999972 -12.580112 90)
			(size 0.3556 0.3556)
			(layers "F.Cu" "F.Mask" "F.Paste")
			(net "TP_PCH_RSVD15")
		)
		(pad "C9" smd circle
			(at -12.999974 -12.480036 90)
			(size 0.3048 0.3048)
			(layers "F.Cu" "F.Mask" "F.Paste")
			(net "TP_PCH_RSVD19")
		)
		(pad "C11" smd circle
			(at -11.999976 -12.480036 90)
			(size 0.3048 0.3048)
			(layers "F.Cu" "F.Mask" "F.Paste")
			(net "TP_PCH_RSVD18")
		)
		(pad "C13" smd circle
			(at -10.999978 -12.480036 90)
			(size 0.3048 0.3048)
			(layers "F.Cu" "F.Mask" "F.Paste")
			(net "TP_PCH_GDP8_SUSCLK")
		)
		(pad "C15" smd circle
			(at -9.99998 -12.480036 90)
			(size 0.3048 0.3048)
			(layers "F.Cu" "F.Mask" "F.Paste")
			(net "FM_PCH_PWRBTN_N")
		)
		(pad "C18" smd circle
			(at -8.999982 -12.480036 90)
			(size 0.3048 0.3048)
			(layers "F.Cu" "F.Mask" "F.Paste")
			(net "FM_SINT_PRSNT_N")
		)
		(pad "C20" smd circle
			(at -7.999984 -12.480036 90)
			(size 0.3048 0.3048)
			(layers "F.Cu" "F.Mask" "F.Paste")
			(net "CLK_100M_SPRV_DN")
		)
		(pad "C22" smd circle
			(at -6.999986 -12.480036 90)
			(size 0.3048 0.3048)
			(layers "F.Cu" "F.Mask" "F.Paste")
			(net "GND")
		)
		(pad "C24" smd circle
			(at -5.999988 -12.480036 90)
			(size 0.3048 0.3048)
			(layers "F.Cu" "F.Mask" "F.Paste")
			(net "Net_3")
		)
		(pad "C26" smd circle
			(at -4.99999 -12.480036 90)
			(size 0.3048 0.3048)
			(layers "F.Cu" "F.Mask" "F.Paste")
			(net "TP_PCH_RSVD64")
		)
		(pad "C28" smd circle
			(at -3.999992 -12.480036 90)
			(size 0.3048 0.3048)
			(layers "F.Cu" "F.Mask" "F.Paste")
			(net "CLK_100M_PCH_SLOTX24_S2_DP")
		)
		(pad "C30" smd circle
			(at -2.999994 -12.480036 90)
			(size 0.3048 0.3048)
			(layers "F.Cu" "F.Mask" "F.Paste")
			(net "GND")
		)
		(pad "C32" smd circle
			(at -1.999996 -12.480036 90)
			(size 0.3048 0.3048)
			(layers "F.Cu" "F.Mask" "F.Paste")
			(net "TP_CLK_100M_NSSCC0_DP")
		)
		(pad "C34" smd circle
			(at -0.999998 -12.480036 90)
			(size 0.3048 0.3048)
			(layers "F.Cu" "F.Mask" "F.Paste")
			(net "GND")
		)
		(pad "C37" smd circle
			(at 0 -12.480036 90)
			(size 0.3048 0.3048)
			(layers "F.Cu" "F.Mask" "F.Paste")
			(net "GND")
		)
		(pad "C39" smd circle
			(at 0.999998 -12.480036 90)
			(size 0.3048 0.3048)
			(layers "F.Cu" "F.Mask" "F.Paste")
			(net "CLK_100M_PCH_XDP_DP")
		)
		(pad "C41" smd circle
			(at 1.999996 -12.480036 90)
			(size 0.3048 0.3048)
			(layers "F.Cu" "F.Mask" "F.Paste")
			(net "GND")
		)
		(pad "C43" smd circle
			(at 2.999994 -12.480036 90)
			(size 0.3048 0.3048)
			(layers "F.Cu" "F.Mask" "F.Paste")
			(net "DMI_CPU0_PCH_TX_C_DN<1>")
		)
		(pad "C45" smd circle
			(at 3.999992 -12.480036 90)
			(size 0.3048 0.3048)
			(layers "F.Cu" "F.Mask" "F.Paste")
			(net "DMI_CPU0_PCH_TX_C_DN<3>")
		)
		(pad "C48" smd circle
			(at 4.99999 -12.480036 90)
			(size 0.3048 0.3048)
			(layers "F.Cu" "F.Mask" "F.Paste")
			(net "P3E_CPU0_PE1_PCH_TXN<0>")
		)
		(pad "C50" smd circle
			(at 5.999988 -12.480036 90)
			(size 0.3048 0.3048)
			(layers "F.Cu" "F.Mask" "F.Paste")
			(net "P3E_CPU0_PE1_PCH_TXN<2>")
		)
	)
)
